# TIMECARD (Time Appliance Project (Time Card)) — schematic netlist excerpt (pin names and nets, part order shuffled) for the footprints in the layout excerpt that follows; sources: Cadence DE-HDL packaged netlist, KiCad conversion of R4006-B0001-02_R01.brd

R400  RESISTOR  100OHM 1%  pkg SMC_0402R_H016  page 26 : \1\ = FPGA_OUT_SMA4_LED_BLUE_N ; \2\ = UNNAMED_14_LED4PV14_I268_1

(kicad_pcb
	(version 20260206)
	(generator "pcbnew")
	(generator_version "10.0")
	(general
		(thickness 1.6)
		(legacy_teardrops no)
	)
	(paper "A4")
	(title_block
		(title "timecard-production-celestica-r4006 — R4006-B0001-02_R01.brd")
		(comment 1 "Time Appliance Project (Time Card) / footprints 16-16 of 1113")
	)
	(layers
		(0 "F.Cu" signal "TOP")
		(4 "In1.Cu" signal "L02_GND1")
		(6 "In2.Cu" signal "L03_SIG1")
		(8 "In3.Cu" signal "L04_GND2")
		(10 "In4.Cu" signal "L05_VCC1")
		(12 "In5.Cu" signal "L06_VCC2")
		(14 "In6.Cu" signal "L07_GND3")
		(16 "In7.Cu" signal "L08_SIG2")
		(18 "In8.Cu" signal "L09_GND4")
		(2 "B.Cu" signal "BOTTOM")
		(9 "F.Adhes" user "F.Adhesive")
		(11 "B.Adhes" user "B.Adhesive")
		(13 "F.Paste" user "Package Geometry/Pastemask Top")
		(15 "B.Paste" user "Package Geometry/Pastemask Bottom")
		(5 "F.SilkS" user "Ref Des/Silkscreen Top")
		(7 "B.SilkS" user "Ref Des/Silkscreen Bottom")
		(1 "F.Mask" user "Board Geometry/Soldermask Top")
		(3 "B.Mask" user "Board Geometry/Soldermask Bottom")
		(17 "Dwgs.User" user "User.Drawings")
		(19 "Cmts.User" user "User.Comments")
		(21 "Eco1.User" user "User.Eco1")
		(23 "Eco2.User" user "User.Eco2")
		(25 "Edge.Cuts" user "Board Geometry/Outline")
		(27 "Margin" user)
		(31 "F.CrtYd" user "Package Geometry/Place Bound Top")
		(29 "B.CrtYd" user "Package Geometry/Place Bound Bottom")
		(35 "F.Fab" user "Ref Des/Assembly Top")
		(33 "B.Fab" user "Ref Des/Assembly Bottom")
	)
	(footprint ""
		(layer "F.Cu")
		(at 19.468338 -45.593 180)
		(property "Reference" "R400"
			(at -3.518662 0.08763 0)
			(unlocked yes)
			(layer "F.SilkS")
			(effects
				(font
					(size 0.7874 0.5842)
					(thickness 0.1524)
				)
			)
		)
		(property "Value" "VAL*"
			(at 0.02032 2.13233 180)
			(unlocked yes)
			(layer "F.Fab")
			(hide yes)
			(effects
				(font
					(size 0.7874 0.5842)
					(thickness 0.1524)
				)
			)
		)
		(property "Device Type" "RESISTOR-G155-11000-01,100OHM,A"
			(at 0.008382 1.210564 180)
			(unlocked yes)
			(layer "F.Fab")
			(hide yes)
			(effects
				(font
					(size 0.7874 0.5842)
					(thickness 0.1524)
				)
			)
		)
		(property "User Part Number" "PARTNUM*"
			(at 0.02032 4.024884 180)
			(unlocked yes)
			(layer "Cmts.User")
			(hide yes)
			(effects
				(font
					(size 0.7874 0.5842)
					(thickness 0.1524)
				)
			)
		)
		(property "Tolerance" "TOL*"
			(at 0.044704 3.05435 180)
			(unlocked yes)
			(layer "Cmts.User")
			(hide yes)
			(effects
				(font
					(size 0.7874 0.5842)
					(thickness 0.1524)
				)
			)
		)
		(duplicate_pad_numbers_are_jumpers no)
		(fp_line
			(start 1.143 0.5588)
			(end 1.143 -0.5588)
			(stroke
				(width 0.1)
				(type default)
			)
			(layer "F.SilkS")
		)
		(fp_line
			(start 1.143 -0.5588)
			(end -1.143 -0.5588)
			(stroke
				(width 0.1)
				(type default)
			)
			(layer "F.SilkS")
		)
		(fp_line
			(start -1.143 0.5588)
			(end 1.143 0.5588)
			(stroke
				(width 0.1)
				(type default)
			)
			(layer "F.SilkS")
		)
		(fp_line
			(start -1.143 -0.5588)
			(end -1.143 0.5588)
			(stroke
				(width 0.1)
				(type default)
			)
			(layer "F.SilkS")
		)
		(fp_poly
			(pts
				(xy -1.143 0.5588) (xy 1.143 0.5588) (xy 1.143 -0.5588) (xy -1.143 -0.5588)
			)
			(stroke
				(width 0)
				(type default)
			)
			(fill no)
			(layer "F.CrtYd")
		)
		(fp_line
			(start 0.508 0.3048)
			(end 0.508 -0.3048)
			(stroke
				(width 0.1)
				(type default)
			)
			(layer "F.Fab")
		)
		(fp_line
			(start 0.508 -0.3048)
			(end -0.508 -0.3048)
			(stroke
				(width 0.1)
				(type default)
			)
			(layer "F.Fab")
		)
		(fp_line
			(start -0.508 0.3048)
			(end 0.508 0.3048)
			(stroke
				(width 0.1)
				(type default)
			)
			(layer "F.Fab")
		)
		(fp_line
			(start -0.508 -0.3048)
			(end -0.508 0.3048)
			(stroke
				(width 0.1)
				(type default)
			)
			(layer "F.Fab")
		)
		(pad "1" smd rect
			(at -0.5334 0 180)
			(size 0.7112 0.6096)
			(layers "F.Cu" "F.Mask" "F.Paste")
			(net "FPGA_OUT_SMA4_LED_BLUE_N")
		)
		(pad "2" smd rect
			(at 0.5334 0 180)
			(size 0.7112 0.6096)
			(layers "F.Cu" "F.Mask" "F.Paste")
			(net "UNNAMED_14_LED4PV14_I268_1")
		)
		(zone
			(layer "F.Cu")
			(hatch none 0.5)
			(connect_pads
				(clearance 0)
			)
			(min_thickness 0.25)
			(keepout
				(tracks not_allowed)
				(vias allowed)
				(pads allowed)
				(copperpour not_allowed)
				(footprints allowed)
			)
			(placement
				(enabled no)
				(sheetname "")
			)
			(fill
				(thermal_gap 0.5)
				(thermal_bridge_width 0.5)
				(island_removal_mode 0)
			)
			(polygon
				(pts
					(xy 19.544538 -45.8978) (xy 19.392138 -45.8978) (xy 19.392138 -45.2882) (xy 19.544538 -45.2882)
				)
			)
		)
		(zone
			(layer "F.Cu")
			(hatch none 0.5)
			(connect_pads
				(clearance 0)
			)
			(min_thickness 0.25)
			(keepout
				(tracks allowed)
				(vias not_allowed)
				(pads allowed)
				(copperpour not_allowed)
				(footprints allowed)
			)
			(placement
				(enabled no)
				(sheetname "")
			)
			(fill
				(thermal_gap 0.5)
				(thermal_bridge_width 0.5)
				(island_removal_mode 0)
			)
			(polygon
				(pts
					(xy 19.544538 -45.8978) (xy 19.392138 -45.8978) (xy 19.392138 -45.2882) (xy 19.544538 -45.2882)
				)
			)
		)
	)
)
